# BASEBOARD_FAB2 (Tioga Pass) — schematic netlist excerpt (pin names and nets, part order shuffled) for the footprints in the layout excerpt that follows; sources: Cadence DE-HDL packaged netlist, KiCad conversion of Wiwynn_Tioga_Pass_MB.brd

R6F7  RES  0.0 5% CHIP  pkg 0402  page 104 : A = CLK_156M_OSC_BRD_CPU0_DN ; B = CLK_156M_OSC_CPU0_HFI_DN
R1W32  RES  330 5% CHIP  pkg 0402  page 89 : A = FM_ADR_COMPLETE_R ; B = FM_ADR_COMPLETE_CPU0_R
C4D47  CAP  0.22UF 16V 10% X7R  pkg 0402  page 204 : A = P5V_STBY ; B = GND

(kicad_pcb
	(version 20260206)
	(generator "pcbnew")
	(generator_version "10.0")
	(general
		(thickness 1.6)
		(legacy_teardrops no)
	)
	(paper "A4")
	(title_block
		(title "Wiwynn_Tioga_Pass_MB.brd")
		(comment 1 "Tioga Pass / footprints 1594-1596 of 4770")
	)
	(layers
		(0 "F.Cu" signal "TOP")
		(4 "In1.Cu" signal "L2GND")
		(6 "In2.Cu" signal "L3")
		(8 "In3.Cu" signal "L4GND")
		(10 "In4.Cu" signal "L5")
		(12 "In5.Cu" signal "L6GND")
		(14 "In6.Cu" signal "L7VCC")
		(16 "In7.Cu" signal "L8VCC")
		(18 "In8.Cu" signal "L9GND")
		(20 "In9.Cu" signal "L10")
		(22 "In10.Cu" signal "L11GND")
		(24 "In11.Cu" signal "L12")
		(26 "In12.Cu" signal "L13GND")
		(2 "B.Cu" signal "BOTTOM")
		(9 "F.Adhes" user "F.Adhesive")
		(11 "B.Adhes" user "B.Adhesive")
		(13 "F.Paste" user "Package Geometry/Pastemask Top")
		(15 "B.Paste" user "Package Geometry/Pastemask Bottom")
		(5 "F.SilkS" user "Ref Des/Silkscreen Top")
		(7 "B.SilkS" user "Ref Des/Silkscreen Bottom")
		(1 "F.Mask" user "Board Geometry/Soldermask Top")
		(3 "B.Mask" user "Board Geometry/Soldermask Bottom")
		(17 "Dwgs.User" user "User.Drawings")
		(19 "Cmts.User" user "User.Comments")
		(21 "Eco1.User" user "User.Eco1")
		(23 "Eco2.User" user "User.Eco2")
		(25 "Edge.Cuts" user "Board Geometry/Outline")
		(27 "Margin" user)
		(31 "F.CrtYd" user "Package Geometry/Place Bound Top")
		(29 "B.CrtYd" user "Package Geometry/Place Bound Bottom")
		(35 "F.Fab" user "Ref Des/Assembly Top")
		(33 "B.Fab" user "Ref Des/Assembly Bottom")
	)
	(footprint ""
		(layer "F.Cu")
		(at 317.9826 -29.696918 90)
		(property "Reference" "R6F7"
			(at 0 0 90)
			(layer "F.SilkS")
			(hide yes)
			(effects
				(font
					(size 1.27 1.27)
				)
			)
		)
		(property "Value" ""
			(at 0 0 90)
			(layer "F.Fab")
			(effects
				(font
					(size 1.27 1.27)
				)
			)
		)
		(duplicate_pad_numbers_are_jumpers no)
		(fp_poly
			(pts
				(xy -0.2794 -0.1016) (xy 0.2794 -0.1016) (xy 0.2794 0.9906) (xy -0.2794 0.9906)
			)
			(stroke
				(width 0)
				(type default)
			)
			(fill no)
			(layer "F.CrtYd")
		)
		(fp_line
			(start 0.2794 -0.1016)
			(end -0.2794 -0.1016)
			(stroke
				(width 0.1)
				(type default)
			)
			(layer "F.Fab")
		)
		(fp_line
			(start -0.2794 -0.1016)
			(end -0.2794 0.9906)
			(stroke
				(width 0.1)
				(type default)
			)
			(layer "F.Fab")
		)
		(fp_line
			(start 0.2794 0.9906)
			(end 0.2794 -0.1016)
			(stroke
				(width 0.1)
				(type default)
			)
			(layer "F.Fab")
		)
		(fp_line
			(start -0.2794 0.9906)
			(end 0.2794 0.9906)
			(stroke
				(width 0.1)
				(type default)
			)
			(layer "F.Fab")
		)
		(pad "1" smd rect
			(at 0 0 90)
			(size 0.508 0.508)
			(layers "F.Cu" "F.Mask" "F.Paste")
			(net "CLK_156M_OSC_BRD_CPU0_DN")
		)
		(pad "2" smd rect
			(at 0 0.889 90)
			(size 0.508 0.508)
			(layers "F.Cu" "F.Mask" "F.Paste")
			(net "CLK_156M_OSC_CPU0_HFI_DN")
		)
		(zone
			(layer "F.Cu")
			(hatch none 0.5)
			(connect_pads
				(clearance 0)
			)
			(min_thickness 0.25)
			(keepout
				(tracks allowed)
				(vias not_allowed)
				(pads allowed)
				(copperpour not_allowed)
				(footprints allowed)
			)
			(placement
				(enabled no)
				(sheetname "")
			)
			(fill
				(thermal_gap 0.5)
				(thermal_bridge_width 0.5)
				(island_removal_mode 0)
			)
			(polygon
				(pts
					(xy 318.2366 -29.442918) (xy 318.2366 -29.950918) (xy 318.6176 -29.950918) (xy 318.6176 -29.442918)
				)
			)
		)
		(zone
			(layer "F.Cu")
			(hatch none 0.5)
			(connect_pads
				(clearance 0)
			)
			(min_thickness 0.25)
			(keepout
				(tracks not_allowed)
				(vias allowed)
				(pads allowed)
				(copperpour not_allowed)
				(footprints allowed)
			)
			(placement
				(enabled no)
				(sheetname "")
			)
			(fill
				(thermal_gap 0.5)
				(thermal_bridge_width 0.5)
				(island_removal_mode 0)
			)
			(polygon
				(pts
					(xy 318.6176 -29.442918) (xy 318.6176 -29.950918) (xy 318.2366 -29.950918) (xy 318.2366 -29.442918)
				)
			)
		)
	)
	(footprint ""
		(layer "F.Cu")
		(at 311.34685 -35.615626)
		(property "Reference" "R1W32"
			(at -0.8382 -0.67818 0)
			(unlocked yes)
			(layer "F.SilkS")
			(effects
				(font
					(size 0.4064 0.254)
					(thickness 0.1524)
				)
				(justify left)
			)
		)
		(property "Value" ""
			(at 0 0 0)
			(layer "F.Fab")
			(effects
				(font
					(size 1.27 1.27)
				)
			)
		)
		(duplicate_pad_numbers_are_jumpers no)
		(fp_poly
			(pts
				(xy -0.2794 -0.1016) (xy 0.2794 -0.1016) (xy 0.2794 0.9906) (xy -0.2794 0.9906)
			)
			(stroke
				(width 0)
				(type default)
			)
			(fill no)
			(layer "F.CrtYd")
		)
		(fp_line
			(start -0.2794 -0.1016)
			(end -0.2794 0.9906)
			(stroke
				(width 0.1)
				(type default)
			)
			(layer "F.Fab")
		)
		(fp_line
			(start -0.2794 0.9906)
			(end 0.2794 0.9906)
			(stroke
				(width 0.1)
				(type default)
			)
			(layer "F.Fab")
		)
		(fp_line
			(start 0.2794 -0.1016)
			(end -0.2794 -0.1016)
			(stroke
				(width 0.1)
				(type default)
			)
			(layer "F.Fab")
		)
		(fp_line
			(start 0.2794 0.9906)
			(end 0.2794 -0.1016)
			(stroke
				(width 0.1)
				(type default)
			)
			(layer "F.Fab")
		)
		(pad "1" smd rect
			(at 0 0)
			(size 0.508 0.508)
			(layers "F.Cu" "F.Mask" "F.Paste")
			(net "FM_ADR_COMPLETE_R")
		)
		(pad "2" smd rect
			(at 0 0.889)
			(size 0.508 0.508)
			(layers "F.Cu" "F.Mask" "F.Paste")
			(net "FM_ADR_COMPLETE_CPU0_R")
		)
		(zone
			(layer "F.Cu")
			(hatch none 0.5)
			(connect_pads
				(clearance 0)
			)
			(min_thickness 0.25)
			(keepout
				(tracks allowed)
				(vias not_allowed)
				(pads allowed)
				(copperpour not_allowed)
				(footprints allowed)
			)
			(placement
				(enabled no)
				(sheetname "")
			)
			(fill
				(thermal_gap 0.5)
				(thermal_bridge_width 0.5)
				(island_removal_mode 0)
			)
			(polygon
				(pts
					(xy 311.09285 -35.361626) (xy 311.60085 -35.361626) (xy 311.60085 -34.980626) (xy 311.09285 -34.980626)
				)
			)
		)
		(zone
			(layer "F.Cu")
			(hatch none 0.5)
			(connect_pads
				(clearance 0)
			)
			(min_thickness 0.25)
			(keepout
				(tracks not_allowed)
				(vias allowed)
				(pads allowed)
				(copperpour not_allowed)
				(footprints allowed)
			)
			(placement
				(enabled no)
				(sheetname "")
			)
			(fill
				(thermal_gap 0.5)
				(thermal_bridge_width 0.5)
				(island_removal_mode 0)
			)
			(polygon
				(pts
					(xy 311.09285 -34.980626) (xy 311.60085 -34.980626) (xy 311.60085 -35.361626) (xy 311.09285 -35.361626)
				)
			)
		)
	)
	(footprint ""
		(layer "F.Cu")
		(at 198.178928 -85.733382 90)
		(property "Reference" "C4D47"
			(at 0 0 90)
			(layer "F.SilkS")
			(hide yes)
			(effects
				(font
					(size 1.27 1.27)
				)
			)
		)
		(property "Value" ""
			(at 0 0 90)
			(layer "F.Fab")
			(effects
				(font
					(size 1.27 1.27)
				)
			)
		)
		(duplicate_pad_numbers_are_jumpers no)
		(fp_rect
			(start 0.3048 0.9906)
			(end -0.3048 -0.1016)
			(stroke
				(width 0)
				(type default)
			)
			(fill no)
			(layer "F.CrtYd")
		)
		(fp_line
			(start 0.3048 -0.1016)
			(end -0.3048 -0.1016)
			(stroke
				(width 0.1)
				(type default)
			)
			(layer "F.Fab")
		)
		(fp_line
			(start -0.3048 -0.1016)
			(end -0.3048 0.9906)
			(stroke
				(width 0.1)
				(type default)
			)
			(layer "F.Fab")
		)
		(fp_line
			(start 0.3048 0.9906)
			(end 0.3048 -0.1016)
			(stroke
				(width 0.1)
				(type default)
			)
			(layer "F.Fab")
		)
		(fp_line
			(start -0.3048 0.9906)
			(end 0.3048 0.9906)
			(stroke
				(width 0.1)
				(type default)
			)
			(layer "F.Fab")
		)
		(pad "1" smd rect
			(at 0 0 90)
			(size 0.508 0.508)
			(layers "F.Cu" "F.Mask" "F.Paste")
			(net "P5V_STBY")
		)
		(pad "2" smd rect
			(at 0 0.889 90)
			(size 0.508 0.508)
			(layers "F.Cu" "F.Mask" "F.Paste")
			(net "GND")
		)
		(zone
			(layer "F.Cu")
			(hatch none 0.5)
			(connect_pads
				(clearance 0)
			)
			(min_thickness 0.25)
			(keepout
				(tracks allowed)
				(vias not_allowed)
				(pads allowed)
				(copperpour not_allowed)
				(footprints allowed)
			)
			(placement
				(enabled no)
				(sheetname "")
			)
			(fill
				(thermal_gap 0.5)
				(thermal_bridge_width 0.5)
				(island_removal_mode 0)
			)
			(polygon
				(pts
					(xy 198.813928 -85.987382) (xy 198.432928 -85.987382) (xy 198.432928 -85.479382) (xy 198.813928 -85.479382)
				)
			)
		)
		(zone
			(layer "F.Cu")
			(hatch none 0.5)
			(connect_pads
				(clearance 0)
			)
			(min_thickness 0.25)
			(keepout
				(tracks not_allowed)
				(vias allowed)
				(pads allowed)
				(copperpour not_allowed)
				(footprints allowed)
			)
			(placement
				(enabled no)
				(sheetname "")
			)
			(fill
				(thermal_gap 0.5)
				(thermal_bridge_width 0.5)
				(island_removal_mode 0)
			)
			(polygon
				(pts
					(xy 198.813928 -85.987382) (xy 198.432928 -85.987382) (xy 198.432928 -85.479382) (xy 198.813928 -85.479382)
				)
			)
		)
	)
)
